# TIMECARD (Time Appliance Project (Time Card)) — schematic netlist excerpt (pin names and nets, part order shuffled) for the footprints in the layout excerpt that follows; sources: Cadence DE-HDL packaged netlist, KiCad conversion of R4006-B0001-02_R01.brd

R473  RESISTOR  0OHM -  pkg SMC_0402R_H016  page 24 : \1\ = R_FT4232_I2C_SDA_IN ; \2\ = FT4232_I2C_SDA
R411  RESISTOR  1KOHM 1%  pkg SMC_0402R_H016  page 17 : \1\ = UNNAMED_6_LM75BDPTSSOP8_I81_A2 ; \2\ = SG

(kicad_pcb
	(version 20260206)
	(generator "pcbnew")
	(generator_version "10.0")
	(general
		(thickness 1.6)
		(legacy_teardrops no)
	)
	(paper "A4")
	(title_block
		(title "timecard-production-celestica-r4006 — R4006-B0001-02_R01.brd")
		(comment 1 "Time Appliance Project (Time Card) / footprints 944-945 of 1113")
	)
	(layers
		(0 "F.Cu" signal "TOP")
		(4 "In1.Cu" signal "L02_GND1")
		(6 "In2.Cu" signal "L03_SIG1")
		(8 "In3.Cu" signal "L04_GND2")
		(10 "In4.Cu" signal "L05_VCC1")
		(12 "In5.Cu" signal "L06_VCC2")
		(14 "In6.Cu" signal "L07_GND3")
		(16 "In7.Cu" signal "L08_SIG2")
		(18 "In8.Cu" signal "L09_GND4")
		(2 "B.Cu" signal "BOTTOM")
		(9 "F.Adhes" user "F.Adhesive")
		(11 "B.Adhes" user "B.Adhesive")
		(13 "F.Paste" user "Package Geometry/Pastemask Top")
		(15 "B.Paste" user "Package Geometry/Pastemask Bottom")
		(5 "F.SilkS" user "Ref Des/Silkscreen Top")
		(7 "B.SilkS" user "Ref Des/Silkscreen Bottom")
		(1 "F.Mask" user "Board Geometry/Soldermask Top")
		(3 "B.Mask" user "Board Geometry/Soldermask Bottom")
		(17 "Dwgs.User" user "User.Drawings")
		(19 "Cmts.User" user "User.Comments")
		(21 "Eco1.User" user "User.Eco1")
		(23 "Eco2.User" user "User.Eco2")
		(25 "Edge.Cuts" user "Board Geometry/Outline")
		(27 "Margin" user)
		(31 "F.CrtYd" user "Package Geometry/Place Bound Top")
		(29 "B.CrtYd" user "Package Geometry/Place Bound Bottom")
		(35 "F.Fab" user "Ref Des/Assembly Top")
		(33 "B.Fab" user "Ref Des/Assembly Bottom")
	)
	(footprint ""
		(layer "B.Cu")
		(at 18.415 -80.137)
		(property "Reference" "R473"
			(at 3.81 0.29337 0)
			(unlocked yes)
			(layer "B.SilkS")
			(effects
				(font
					(size 0.7874 0.5842)
					(thickness 0.1524)
				)
				(justify mirror)
			)
		)
		(property "Value" "VAL*"
			(at -0.02032 2.13233 0)
			(unlocked yes)
			(layer "B.Fab")
			(hide yes)
			(effects
				(font
					(size 0.7874 0.5842)
					(thickness 0.1524)
				)
				(justify mirror)
			)
		)
		(property "Tolerance" "TOL*"
			(at -0.044704 3.05435 0)
			(unlocked yes)
			(layer "Cmts.User")
			(hide yes)
			(effects
				(font
					(size 0.7874 0.5842)
					(thickness 0.1524)
				)
				(justify mirror)
			)
		)
		(property "User Part Number" "PARTNUM*"
			(at -0.02032 4.024884 0)
			(unlocked yes)
			(layer "Cmts.User")
			(hide yes)
			(effects
				(font
					(size 0.7874 0.5842)
					(thickness 0.1524)
				)
				(justify mirror)
			)
		)
		(property "Device Type" "RESISTOR-G155-100R0-J0,0OHM,-"
			(at -0.008382 1.210564 0)
			(unlocked yes)
			(layer "B.Fab")
			(hide yes)
			(effects
				(font
					(size 0.7874 0.5842)
					(thickness 0.1524)
				)
				(justify mirror)
			)
		)
		(duplicate_pad_numbers_are_jumpers no)
		(fp_line
			(start -1.143 -0.5588)
			(end 1.143 -0.5588)
			(stroke
				(width 0.1)
				(type default)
			)
			(layer "B.SilkS")
		)
		(fp_line
			(start -1.143 0.5588)
			(end -1.143 -0.5588)
			(stroke
				(width 0.1)
				(type default)
			)
			(layer "B.SilkS")
		)
		(fp_line
			(start 1.143 -0.5588)
			(end 1.143 0.5588)
			(stroke
				(width 0.1)
				(type default)
			)
			(layer "B.SilkS")
		)
		(fp_line
			(start 1.143 0.5588)
			(end -1.143 0.5588)
			(stroke
				(width 0.1)
				(type default)
			)
			(layer "B.SilkS")
		)
		(fp_poly
			(pts
				(xy 1.143 0.5588) (xy -1.143 0.5588) (xy -1.143 -0.5588) (xy 1.143 -0.5588)
			)
			(stroke
				(width 0)
				(type default)
			)
			(fill no)
			(layer "B.CrtYd")
		)
		(fp_line
			(start -0.508 -0.3048)
			(end 0.508 -0.3048)
			(stroke
				(width 0.1)
				(type default)
			)
			(layer "B.Fab")
		)
		(fp_line
			(start -0.508 0.3048)
			(end -0.508 -0.3048)
			(stroke
				(width 0.1)
				(type default)
			)
			(layer "B.Fab")
		)
		(fp_line
			(start 0.508 -0.3048)
			(end 0.508 0.3048)
			(stroke
				(width 0.1)
				(type default)
			)
			(layer "B.Fab")
		)
		(fp_line
			(start 0.508 0.3048)
			(end -0.508 0.3048)
			(stroke
				(width 0.1)
				(type default)
			)
			(layer "B.Fab")
		)
		(pad "1" smd rect
			(at 0.5334 0 180)
			(size 0.7112 0.6096)
			(layers "B.Cu" "B.Mask" "B.Paste")
			(net "R_FT4232_I2C_SDA_IN")
		)
		(pad "2" smd rect
			(at -0.5334 0 180)
			(size 0.7112 0.6096)
			(layers "B.Cu" "B.Mask" "B.Paste")
			(net "FT4232_I2C_SDA")
		)
		(zone
			(layer "B.Cu")
			(hatch none 0.5)
			(connect_pads
				(clearance 0)
			)
			(min_thickness 0.25)
			(keepout
				(tracks not_allowed)
				(vias allowed)
				(pads allowed)
				(copperpour not_allowed)
				(footprints allowed)
			)
			(placement
				(enabled no)
				(sheetname "")
			)
			(fill
				(thermal_gap 0.5)
				(thermal_bridge_width 0.5)
				(island_removal_mode 0)
			)
			(polygon
				(pts
					(xy 18.4912 -79.8322) (xy 18.4912 -80.4418) (xy 18.3388 -80.4418) (xy 18.3388 -79.8322)
				)
			)
		)
		(zone
			(layer "B.Cu")
			(hatch none 0.5)
			(connect_pads
				(clearance 0)
			)
			(min_thickness 0.25)
			(keepout
				(tracks allowed)
				(vias not_allowed)
				(pads allowed)
				(copperpour not_allowed)
				(footprints allowed)
			)
			(placement
				(enabled no)
				(sheetname "")
			)
			(fill
				(thermal_gap 0.5)
				(thermal_bridge_width 0.5)
				(island_removal_mode 0)
			)
			(polygon
				(pts
					(xy 18.4912 -79.8322) (xy 18.4912 -80.4418) (xy 18.3388 -80.4418) (xy 18.3388 -79.8322)
				)
			)
		)
	)
	(footprint ""
		(layer "B.Cu")
		(at 162.56 -24.511 180)
		(property "Reference" "R411"
			(at 0.381 -1.43637 0)
			(unlocked yes)
			(layer "B.SilkS")
			(effects
				(font
					(size 0.7874 0.5842)
					(thickness 0.1524)
				)
				(justify mirror)
			)
		)
		(property "Value" "VAL*"
			(at -0.02032 2.13233 180)
			(unlocked yes)
			(layer "B.Fab")
			(hide yes)
			(effects
				(font
					(size 0.7874 0.5842)
					(thickness 0.1524)
				)
				(justify mirror)
			)
		)
		(property "Tolerance" "TOL*"
			(at -0.044704 3.05435 180)
			(unlocked yes)
			(layer "Cmts.User")
			(hide yes)
			(effects
				(font
					(size 0.7874 0.5842)
					(thickness 0.1524)
				)
				(justify mirror)
			)
		)
		(property "User Part Number" "PARTNUM*"
			(at -0.02032 4.024884 180)
			(unlocked yes)
			(layer "Cmts.User")
			(hide yes)
			(effects
				(font
					(size 0.7874 0.5842)
					(thickness 0.1524)
				)
				(justify mirror)
			)
		)
		(property "Device Type" "RESISTOR-G155-11001-01,1KOHM,1%"
			(at -0.008382 1.210564 180)
			(unlocked yes)
			(layer "B.Fab")
			(hide yes)
			(effects
				(font
					(size 0.7874 0.5842)
					(thickness 0.1524)
				)
				(justify mirror)
			)
		)
		(duplicate_pad_numbers_are_jumpers no)
		(fp_line
			(start 1.143 0.5588)
			(end -1.143 0.5588)
			(stroke
				(width 0.1)
				(type default)
			)
			(layer "B.SilkS")
		)
		(fp_line
			(start 1.143 -0.5588)
			(end 1.143 0.5588)
			(stroke
				(width 0.1)
				(type default)
			)
			(layer "B.SilkS")
		)
		(fp_line
			(start -1.143 0.5588)
			(end -1.143 -0.5588)
			(stroke
				(width 0.1)
				(type default)
			)
			(layer "B.SilkS")
		)
		(fp_line
			(start -1.143 -0.5588)
			(end 1.143 -0.5588)
			(stroke
				(width 0.1)
				(type default)
			)
			(layer "B.SilkS")
		)
		(fp_rect
			(start 1.143 0.5588)
			(end -1.143 -0.5588)
			(stroke
				(width 0)
				(type default)
			)
			(fill no)
			(layer "B.CrtYd")
		)
		(fp_line
			(start 0.508 0.3048)
			(end -0.508 0.3048)
			(stroke
				(width 0.1)
				(type default)
			)
			(layer "B.Fab")
		)
		(fp_line
			(start 0.508 -0.3048)
			(end 0.508 0.3048)
			(stroke
				(width 0.1)
				(type default)
			)
			(layer "B.Fab")
		)
		(fp_line
			(start -0.508 0.3048)
			(end -0.508 -0.3048)
			(stroke
				(width 0.1)
				(type default)
			)
			(layer "B.Fab")
		)
		(fp_line
			(start -0.508 -0.3048)
			(end 0.508 -0.3048)
			(stroke
				(width 0.1)
				(type default)
			)
			(layer "B.Fab")
		)
		(pad "1" smd rect
			(at 0.5334 0)
			(size 0.7112 0.6096)
			(layers "B.Cu" "B.Mask" "B.Paste")
			(net "UNNAMED_6_LM75BDPTSSOP8_I81_A2")
		)
		(pad "2" smd rect
			(at -0.5334 0)
			(size 0.7112 0.6096)
			(layers "B.Cu" "B.Mask" "B.Paste")
			(net "SG")
		)
		(zone
			(layer "B.Cu")
			(hatch none 0.5)
			(connect_pads
				(clearance 0)
			)
			(min_thickness 0.25)
			(keepout
				(tracks allowed)
				(vias not_allowed)
				(pads allowed)
				(copperpour not_allowed)
				(footprints allowed)
			)
			(placement
				(enabled no)
				(sheetname "")
			)
			(fill
				(thermal_gap 0.5)
				(thermal_bridge_width 0.5)
				(island_removal_mode 0)
			)
			(polygon
				(pts
					(xy 162.4838 -24.8158) (xy 162.4838 -24.2062) (xy 162.6362 -24.2062) (xy 162.6362 -24.8158)
				)
			)
		)
		(zone
			(layer "B.Cu")
			(hatch none 0.5)
			(connect_pads
				(clearance 0)
			)
			(min_thickness 0.25)
			(keepout
				(tracks not_allowed)
				(vias allowed)
				(pads allowed)
				(copperpour not_allowed)
				(footprints allowed)
			)
			(placement
				(enabled no)
				(sheetname "")
			)
			(fill
				(thermal_gap 0.5)
				(thermal_bridge_width 0.5)
				(island_removal_mode 0)
			)
			(polygon
				(pts
					(xy 162.4838 -24.8158) (xy 162.4838 -24.2062) (xy 162.6362 -24.2062) (xy 162.6362 -24.8158)
				)
			)
		)
	)
)
